# BASEBOARD_FAB2 (Tioga Pass) — schematic netlist excerpt (pin names and nets, part order shuffled) for the footprints in the layout excerpt that follows; sources: Cadence DE-HDL packaged netlist, KiCad conversion of Wiwynn_Tioga_Pass_MB.brd

C9L9  CAPP  470UF 2.5V 20% ALUM  pkg 3018  page 228 : A = PVDDQ_KLM ; B = GND

VR32W1  LMV431AIMFX-GP  pkg DISCRET-G5  page 185
  REF  = VREF_LMV431_1V42
  CATHODE  = P1V8_M2
  ANODE  = GND

(kicad_pcb
	(version 20260206)
	(generator "pcbnew")
	(generator_version "10.0")
	(general
		(thickness 1.6)
		(legacy_teardrops no)
	)
	(paper "A4")
	(title_block
		(title "Wiwynn_Tioga_Pass_MB.brd")
		(comment 1 "Tioga Pass / footprints 3403-3404 of 4770")
	)
	(layers
		(0 "F.Cu" signal "TOP")
		(4 "In1.Cu" signal "L2GND")
		(6 "In2.Cu" signal "L3")
		(8 "In3.Cu" signal "L4GND")
		(10 "In4.Cu" signal "L5")
		(12 "In5.Cu" signal "L6GND")
		(14 "In6.Cu" signal "L7VCC")
		(16 "In7.Cu" signal "L8VCC")
		(18 "In8.Cu" signal "L9GND")
		(20 "In9.Cu" signal "L10")
		(22 "In10.Cu" signal "L11GND")
		(24 "In11.Cu" signal "L12")
		(26 "In12.Cu" signal "L13GND")
		(2 "B.Cu" signal "BOTTOM")
		(9 "F.Adhes" user "F.Adhesive")
		(11 "B.Adhes" user "B.Adhesive")
		(13 "F.Paste" user "Package Geometry/Pastemask Top")
		(15 "B.Paste" user "Package Geometry/Pastemask Bottom")
		(5 "F.SilkS" user "Ref Des/Silkscreen Top")
		(7 "B.SilkS" user "Ref Des/Silkscreen Bottom")
		(1 "F.Mask" user "Board Geometry/Soldermask Top")
		(3 "B.Mask" user "Board Geometry/Soldermask Bottom")
		(17 "Dwgs.User" user "User.Drawings")
		(19 "Cmts.User" user "User.Comments")
		(21 "Eco1.User" user "User.Eco1")
		(23 "Eco2.User" user "User.Eco2")
		(25 "Edge.Cuts" user "Board Geometry/Outline")
		(27 "Margin" user)
		(31 "F.CrtYd" user "Package Geometry/Place Bound Top")
		(29 "B.CrtYd" user "Package Geometry/Place Bound Bottom")
		(35 "F.Fab" user "Ref Des/Assembly Top")
		(33 "B.Fab" user "Ref Des/Assembly Bottom")
	)
	(footprint ""
		(layer "B.Cu")
		(at 395.351 -22.86 -90)
		(property "Reference" "VR32W1"
			(at 0 0 90)
			(layer "B.SilkS")
			(hide yes)
			(effects
				(font
					(size 1.27 1.27)
				)
				(justify mirror)
			)
		)
		(property "Value" "*"
			(at 0 -4.33705 270)
			(unlocked yes)
			(layer "B.Fab")
			(hide yes)
			(effects
				(font
					(size 0.889 0.889)
					(thickness 0.1524)
				)
				(justify mirror)
			)
		)
		(property "Device Type" "LMV431AIMFX-GP_DISCRET-G5-LMV4A"
			(at 0 -5.73405 270)
			(unlocked yes)
			(layer "B.Fab")
			(hide yes)
			(effects
				(font
					(size 0.889 0.889)
					(thickness 0.1524)
				)
				(justify mirror)
			)
		)
		(duplicate_pad_numbers_are_jumpers no)
		(fp_line
			(start -1.7018 0.254)
			(end -1.7018 -0.254)
			(stroke
				(width 0.1524)
				(type default)
			)
			(layer "B.SilkS")
		)
		(fp_line
			(start 1.7018 0.254)
			(end -1.7018 0.254)
			(stroke
				(width 0.1524)
				(type default)
			)
			(layer "B.SilkS")
		)
		(fp_line
			(start -1.7018 -0.254)
			(end 1.7018 -0.254)
			(stroke
				(width 0.1524)
				(type default)
			)
			(layer "B.SilkS")
		)
		(fp_line
			(start 1.7018 -0.254)
			(end 1.7018 0.254)
			(stroke
				(width 0.1524)
				(type default)
			)
			(layer "B.SilkS")
		)
		(fp_rect
			(start 1.778 1.9812)
			(end -1.778 -1.9812)
			(stroke
				(width 0)
				(type default)
			)
			(fill no)
			(layer "B.CrtYd")
		)
		(fp_rect
			(start 1.778 1.9812)
			(end -1.778 -1.9812)
			(stroke
				(width 0)
				(type default)
			)
			(fill no)
			(layer "B.Fab")
		)
		(pad "1" smd custom
			(at 1.016 1.1176 90)
			(size 0.254 0.254)
			(layers "B.Cu" "B.Mask" "B.Paste")
			(net "VREF_LMV431_1V42")
			(options
				(clearance outline)
				(anchor circle)
			)
			(primitives
				(gr_poly
					(pts
						(arc
							(start -0.508 0.4064)
							(mid -0.448484 0.550084)
							(end -0.3048 0.6096)
						)
						(arc
							(start 0.3048 0.6096)
							(mid 0.448484 0.550084)
							(end 0.508 0.4064)
						)
						(arc
							(start 0.508 -0.4064)
							(mid 0.448484 -0.550084)
							(end 0.3048 -0.6096)
						)
						(arc
							(start -0.3048 -0.6096)
							(mid -0.448484 -0.550084)
							(end -0.508 -0.4064)
						)
					)
					(width 0)
					(fill yes)
				)
			)
		)
		(pad "2" smd custom
			(at -1.016 1.1176 90)
			(size 0.254 0.254)
			(layers "B.Cu" "B.Mask" "B.Paste")
			(net "P1V8_M2")
			(options
				(clearance outline)
				(anchor circle)
			)
			(primitives
				(gr_poly
					(pts
						(arc
							(start -0.508 0.4064)
							(mid -0.448484 0.550084)
							(end -0.3048 0.6096)
						)
						(arc
							(start 0.3048 0.6096)
							(mid 0.448484 0.550084)
							(end 0.508 0.4064)
						)
						(arc
							(start 0.508 -0.4064)
							(mid 0.448484 -0.550084)
							(end 0.3048 -0.6096)
						)
						(arc
							(start -0.3048 -0.6096)
							(mid -0.448484 -0.550084)
							(end -0.508 -0.4064)
						)
					)
					(width 0)
					(fill yes)
				)
			)
		)
		(pad "3" smd custom
			(at 0 -1.1176 90)
			(size 0.254 0.254)
			(layers "B.Cu" "B.Mask" "B.Paste")
			(net "GND")
			(options
				(clearance outline)
				(anchor circle)
			)
			(primitives
				(gr_poly
					(pts
						(arc
							(start -0.508 0.4064)
							(mid -0.448484 0.550084)
							(end -0.3048 0.6096)
						)
						(arc
							(start 0.3048 0.6096)
							(mid 0.448484 0.550084)
							(end 0.508 0.4064)
						)
						(arc
							(start 0.508 -0.4064)
							(mid 0.448484 -0.550084)
							(end 0.3048 -0.6096)
						)
						(arc
							(start -0.3048 -0.6096)
							(mid -0.448484 -0.550084)
							(end -0.508 -0.4064)
						)
					)
					(width 0)
					(fill yes)
				)
			)
		)
	)
	(footprint ""
		(layer "B.Cu")
		(at 18.0594 -144.2974 -90)
		(property "Reference" "C9L9"
			(at -1.97993 9.1694 0)
			(unlocked yes)
			(layer "B.SilkS")
			(effects
				(font
					(size 0.7874 0.5842)
					(thickness 0.1524)
				)
				(justify mirror)
			)
		)
		(property "Value" ""
			(at 0 0 90)
			(layer "B.Fab")
			(effects
				(font
					(size 1.27 1.27)
				)
				(justify mirror)
			)
		)
		(duplicate_pad_numbers_are_jumpers no)
		(fp_line
			(start -2.286 7.366)
			(end -1.600708 7.366)
			(stroke
				(width 0.1524)
				(type default)
			)
			(layer "B.SilkS")
		)
		(fp_line
			(start -2.286 7.366)
			(end -2.286 1.63195)
			(stroke
				(width 0.1524)
				(type default)
			)
			(layer "B.SilkS")
		)
		(fp_line
			(start 2.286 7.366)
			(end 1.60147 7.366)
			(stroke
				(width 0.1524)
				(type default)
			)
			(layer "B.SilkS")
		)
		(fp_line
			(start 2.286 7.366)
			(end 2.286 1.632712)
			(stroke
				(width 0.1524)
				(type default)
			)
			(layer "B.SilkS")
		)
		(fp_line
			(start -2.504948 1.633728)
			(end -1.6002 1.633728)
			(stroke
				(width 0.1524)
				(type default)
			)
			(layer "B.SilkS")
		)
		(fp_line
			(start 2.563114 1.633728)
			(end 1.6002 1.633728)
			(stroke
				(width 0.1524)
				(type default)
			)
			(layer "B.SilkS")
		)
		(fp_line
			(start -2.504948 -1.616456)
			(end -2.504948 1.633728)
			(stroke
				(width 0.1524)
				(type default)
			)
			(layer "B.SilkS")
		)
		(fp_line
			(start -1.6002 -1.616456)
			(end -2.504948 -1.616456)
			(stroke
				(width 0.1524)
				(type default)
			)
			(layer "B.SilkS")
		)
		(fp_line
			(start 1.6002 -1.616456)
			(end 2.563114 -1.616456)
			(stroke
				(width 0.1524)
				(type default)
			)
			(layer "B.SilkS")
		)
		(fp_line
			(start 2.563114 -1.616456)
			(end 2.563114 1.633728)
			(stroke
				(width 0.1524)
				(type default)
			)
			(layer "B.SilkS")
		)
		(fp_rect
			(start 2.286 -0.254)
			(end -2.286 7.366)
			(stroke
				(width 0)
				(type default)
			)
			(fill no)
			(layer "B.CrtYd")
		)
		(fp_line
			(start -2.286 7.366)
			(end 2.286 7.366)
			(stroke
				(width 0.1)
				(type default)
			)
			(layer "B.Fab")
		)
		(fp_line
			(start 2.286 7.366)
			(end 2.286 -0.254)
			(stroke
				(width 0.1)
				(type default)
			)
			(layer "B.Fab")
		)
		(fp_line
			(start -2.286 -0.254)
			(end -2.286 7.366)
			(stroke
				(width 0.1)
				(type default)
			)
			(layer "B.Fab")
		)
		(fp_line
			(start 2.286 -0.254)
			(end -2.286 -0.254)
			(stroke
				(width 0.1)
				(type default)
			)
			(layer "B.Fab")
		)
		(pad "1" smd rect
			(at 0 0 90)
			(size 2.54 3.048)
			(layers "B.Cu" "B.Mask" "B.Paste")
			(net "PVDDQ_KLM")
		)
		(pad "2" smd rect
			(at 0 7.112 90)
			(size 2.54 3.048)
			(layers "B.Cu" "B.Mask" "B.Paste")
			(net "GND")
		)
	)
)
